(kicad_pcb
	(version 20260206)
	(generator "pcbnew")
	(generator_version "10.0")
	(general
		(thickness 1.6)
		(legacy_teardrops no)
	)
	(paper "A4")
	(title_block
		(title "fcb — 12433-1M.1206WZS1330.brd")
		(comment 1 "Open Vault / Knox (Wiwynn) / footprints 79-84 of 495")
	)
	(layers
		(0 "F.Cu" signal "TOP")
		(4 "In1.Cu" signal "L2GND")
		(6 "In2.Cu" signal "L3VCC")
		(2 "B.Cu" signal "BOTTOM")
		(9 "F.Adhes" user "F.Adhesive")
		(11 "B.Adhes" user "B.Adhesive")
		(13 "F.Paste" user "Package Geometry/Pastemask Top")
		(15 "B.Paste" user "Package Geometry/Pastemask Bottom")
		(5 "F.SilkS" user "Ref Des/Silkscreen Top")
		(7 "B.SilkS" user "Ref Des/Silkscreen Bottom")
		(1 "F.Mask" user "Board Geometry/Soldermask Top")
		(3 "B.Mask" user "Board Geometry/Soldermask Bottom")
		(17 "Dwgs.User" user "User.Drawings")
		(19 "Cmts.User" user "User.Comments")
		(21 "Eco1.User" user "User.Eco1")
		(23 "Eco2.User" user "User.Eco2")
		(25 "Edge.Cuts" user "Board Geometry/Outline")
		(27 "Margin" user)
		(31 "F.CrtYd" user "Package Geometry/Place Bound Top")
		(29 "B.CrtYd" user "Package Geometry/Place Bound Bottom")
		(35 "F.Fab" user "Ref Des/Assembly Top")
		(33 "B.Fab" user "Ref Des/Assembly Bottom")
	)
	(footprint ""
		(layer "F.Cu")
		(at 21.7678 -217.7288 90)
		(property "Reference" "R133"
			(at 0 0 90)
			(layer "F.SilkS")
			(hide yes)
			(effects
				(font
					(size 1.27 1.27)
				)
			)
		)
		(property "Value" "4K7R2F-GP"
			(at 0.064008 -3.993896 90)
			(unlocked yes)
			(layer "F.Fab")
			(hide yes)
			(effects
				(font
					(size 1.016 1.016)
					(thickness 0.1524)
				)
			)
		)
		(property "Device Type" "R402H16"
			(at 0.064008 -5.517896 90)
			(unlocked yes)
			(layer "F.Fab")
			(hide yes)
			(effects
				(font
					(size 1.016 1.016)
					(thickness 0.1524)
				)
			)
		)
		(duplicate_pad_numbers_are_jumpers no)
		(fp_line
			(start 0.508 -0.9398)
			(end -0.508 -0.9398)
			(stroke
				(width 0.1524)
				(type default)
			)
			(layer "F.SilkS")
		)
		(fp_line
			(start -0.508 -0.9398)
			(end -0.508 0.9398)
			(stroke
				(width 0.1524)
				(type default)
			)
			(layer "F.SilkS")
		)
		(fp_rect
			(start -0.508 0.9398)
			(end 0.508 -0.9398)
			(stroke
				(width 0)
				(type default)
			)
			(fill no)
			(layer "F.CrtYd")
		)
		(fp_rect
			(start -0.508 0.9398)
			(end 0.508 -0.9398)
			(stroke
				(width 0)
				(type default)
			)
			(fill no)
			(layer "F.Fab")
		)
		(pad "1" smd custom
			(at 0 -0.4445 90)
			(size 0.1397 0.1397)
			(layers "F.Cu" "F.Mask" "F.Paste")
			(net "P3V3")
			(options
				(clearance outline)
				(anchor circle)
			)
			(primitives
				(gr_poly
					(pts
						(arc
							(start -0.1778 -0.2794)
							(mid -0.249642 -0.249642)
							(end -0.2794 -0.1778)
						)
						(arc
							(start -0.2794 0.1778)
							(mid -0.249642 0.249642)
							(end -0.1778 0.2794)
						)
						(arc
							(start 0.1778 0.2794)
							(mid 0.249642 0.249642)
							(end 0.2794 0.1778)
						)
						(arc
							(start 0.2794 -0.1778)
							(mid 0.249642 -0.249642)
							(end 0.1778 -0.2794)
						)
					)
					(width 0)
					(fill yes)
				)
			)
		)
		(pad "2" smd custom
			(at 0 0.4445 90)
			(size 0.1397 0.1397)
			(layers "F.Cu" "F.Mask" "F.Paste")
			(net "PWM_OUT_FAN3")
			(options
				(clearance outline)
				(anchor circle)
			)
			(primitives
				(gr_poly
					(pts
						(arc
							(start -0.1778 -0.2794)
							(mid -0.249642 -0.249642)
							(end -0.2794 -0.1778)
						)
						(arc
							(start -0.2794 0.1778)
							(mid -0.249642 0.249642)
							(end -0.1778 0.2794)
						)
						(arc
							(start 0.1778 0.2794)
							(mid 0.249642 0.249642)
							(end 0.2794 0.1778)
						)
						(arc
							(start 0.2794 -0.1778)
							(mid 0.249642 -0.249642)
							(end 0.1778 -0.2794)
						)
					)
					(width 0)
					(fill yes)
				)
			)
		)
	)
	(footprint ""
		(layer "F.Cu")
		(at 45.522134 -155.83789 -90)
		(property "Reference" "L2"
			(at 0 0 270)
			(layer "F.SilkS")
			(hide yes)
			(effects
				(font
					(size 1.27 1.27)
				)
			)
		)
		(property "Value" "FCM1608CF-121T03-GP"
			(at -0.0254 -2.8956 270)
			(unlocked yes)
			(layer "F.Fab")
			(hide yes)
			(effects
				(font
					(size 1.016 1.016)
					(thickness 0.1524)
				)
			)
		)
		(property "Device Type" "L1608-UH38"
			(at -0.0254 -4.4196 270)
			(unlocked yes)
			(layer "F.Fab")
			(hide yes)
			(effects
				(font
					(size 1.016 1.016)
					(thickness 0.1524)
				)
			)
		)
		(duplicate_pad_numbers_are_jumpers no)
		(fp_line
			(start 0.254 0)
			(end -0.254 0)
			(stroke
				(width 0.2032)
				(type default)
			)
			(layer "F.SilkS")
		)
		(fp_rect
			(start -0.5842 1.3335)
			(end 0.5842 -1.3335)
			(stroke
				(width 0)
				(type default)
			)
			(fill no)
			(layer "F.CrtYd")
		)
		(fp_rect
			(start -0.5842 1.3335)
			(end 0.5842 -1.3335)
			(stroke
				(width 0)
				(type default)
			)
			(fill no)
			(layer "F.Fab")
		)
		(pad "1" smd custom
			(at 0 -0.762 270)
			(size 0.2159 0.2159)
			(layers "F.Cu" "F.Mask" "F.Paste")
			(net "P3V3")
			(options
				(clearance outline)
				(anchor circle)
			)
			(primitives
				(gr_poly
					(pts
						(arc
							(start -0.3302 -0.4318)
							(mid -0.402042 -0.402042)
							(end -0.4318 -0.3302)
						)
						(arc
							(start -0.4318 0.3302)
							(mid -0.402042 0.402042)
							(end -0.3302 0.4318)
						)
						(arc
							(start 0.3302 0.4318)
							(mid 0.402042 0.402042)
							(end 0.4318 0.3302)
						)
						(arc
							(start 0.4318 -0.3302)
							(mid 0.402042 -0.402042)
							(end 0.3302 -0.4318)
						)
					)
					(width 0)
					(fill yes)
				)
			)
		)
		(pad "2" smd custom
			(at 0 0.762 270)
			(size 0.2159 0.2159)
			(layers "F.Cu" "F.Mask" "F.Paste")
			(net "NCT7904_3VSB")
			(options
				(clearance outline)
				(anchor circle)
			)
			(primitives
				(gr_poly
					(pts
						(arc
							(start -0.3302 -0.4318)
							(mid -0.402042 -0.402042)
							(end -0.4318 -0.3302)
						)
						(arc
							(start -0.4318 0.3302)
							(mid -0.402042 0.402042)
							(end -0.3302 0.4318)
						)
						(arc
							(start 0.3302 0.4318)
							(mid 0.402042 0.402042)
							(end 0.4318 0.3302)
						)
						(arc
							(start 0.4318 -0.3302)
							(mid 0.402042 -0.402042)
							(end 0.3302 -0.4318)
						)
					)
					(width 0)
					(fill yes)
				)
			)
		)
	)
	(footprint ""
		(layer "F.Cu")
		(at 8.001 -417.9062 180)
		(property "Reference" "Q7"
			(at 0 0 180)
			(layer "F.SilkS")
			(hide yes)
			(effects
				(font
					(size 1.27 1.27)
				)
			)
		)
		(property "Value" "PMBS3904-1-GP"
			(at 0 -9.0932 180)
			(unlocked yes)
			(layer "F.Fab")
			(hide yes)
			(effects
				(font
					(size 1.016 1.016)
					(thickness 0.1524)
				)
			)
		)
		(property "Device Type" "SOT-23-10H44"
			(at 0 -10.6172 180)
			(unlocked yes)
			(layer "F.Fab")
			(hide yes)
			(effects
				(font
					(size 1.016 1.016)
					(thickness 0.1524)
				)
			)
		)
		(duplicate_pad_numbers_are_jumpers no)
		(fp_line
			(start 1.651 1.778)
			(end 1.651 -1.778)
			(stroke
				(width 0.1524)
				(type default)
			)
			(layer "F.SilkS")
		)
		(fp_line
			(start 1.651 -1.778)
			(end -1.651 -1.778)
			(stroke
				(width 0.1524)
				(type default)
			)
			(layer "F.SilkS")
		)
		(fp_line
			(start -0.635 1.8796)
			(end -1.7526 1.8796)
			(stroke
				(width 0.3302)
				(type default)
			)
			(layer "F.SilkS")
		)
		(fp_line
			(start -0.71628 2.15265)
			(end -1.26492 2.15265)
			(stroke
				(width 0.0127)
				(type default)
			)
			(layer "F.SilkS")
		)
		(fp_line
			(start -0.719074 2.145538)
			(end -1.265936 2.14122)
			(stroke
				(width 0.0127)
				(type default)
			)
			(layer "F.SilkS")
		)
		(fp_line
			(start -0.9906 1.86309)
			(end -0.701294 2.15265)
			(stroke
				(width 0.0127)
				(type default)
			)
			(layer "F.SilkS")
		)
		(fp_line
			(start -0.994156 1.8669)
			(end -0.987044 1.8669)
			(stroke
				(width 0.0127)
				(type default)
			)
			(layer "F.SilkS")
		)
		(fp_line
			(start -1.003808 1.876552)
			(end -0.977646 1.876552)
			(stroke
				(width 0.0127)
				(type default)
			)
			(layer "F.SilkS")
		)
		(fp_line
			(start -1.013206 1.88595)
			(end -0.967994 1.88595)
			(stroke
				(width 0.0127)
				(type default)
			)
			(layer "F.SilkS")
		)
		(fp_line
			(start -1.022858 1.895602)
			(end -0.958596 1.895602)
			(stroke
				(width 0.0127)
				(type default)
			)
			(layer "F.SilkS")
		)
		(fp_line
			(start -1.032256 1.905)
			(end -0.948944 1.905)
			(stroke
				(width 0.0127)
				(type default)
			)
			(layer "F.SilkS")
		)
		(fp_line
			(start -1.041908 1.914652)
			(end -0.939546 1.914652)
			(stroke
				(width 0.0127)
				(type default)
			)
			(layer "F.SilkS")
		)
		(fp_line
			(start -1.051306 1.92405)
			(end -0.929894 1.92405)
			(stroke
				(width 0.0127)
				(type default)
			)
			(layer "F.SilkS")
		)
		(fp_line
			(start -1.060958 1.933702)
			(end -0.920496 1.933702)
			(stroke
				(width 0.0127)
				(type default)
			)
			(layer "F.SilkS")
		)
		(fp_line
			(start -1.070356 1.9431)
			(end -0.910844 1.9431)
			(stroke
				(width 0.0127)
				(type default)
			)
			(layer "F.SilkS")
		)
		(fp_line
			(start -1.080008 1.952752)
			(end -0.901446 1.952752)
			(stroke
				(width 0.0127)
				(type default)
			)
			(layer "F.SilkS")
		)
		(fp_line
			(start -1.089406 1.96215)
			(end -0.891794 1.96215)
			(stroke
				(width 0.0127)
				(type default)
			)
			(layer "F.SilkS")
		)
		(fp_line
			(start -1.099058 1.971802)
			(end -0.882396 1.971802)
			(stroke
				(width 0.0127)
				(type default)
			)
			(layer "F.SilkS")
		)
		(fp_line
			(start -1.108456 1.9812)
			(end -0.872744 1.9812)
			(stroke
				(width 0.0127)
				(type default)
			)
			(layer "F.SilkS")
		)
		(fp_line
			(start -1.118108 1.990852)
			(end -0.863346 1.990852)
			(stroke
				(width 0.0127)
				(type default)
			)
			(layer "F.SilkS")
		)
		(fp_line
			(start -1.127506 2.00025)
			(end -0.853694 2.00025)
			(stroke
				(width 0.0127)
				(type default)
			)
			(layer "F.SilkS")
		)
		(fp_line
			(start -1.137158 2.009902)
			(end -0.844296 2.009902)
			(stroke
				(width 0.0127)
				(type default)
			)
			(layer "F.SilkS")
		)
		(fp_line
			(start -1.146556 2.0193)
			(end -0.834644 2.0193)
			(stroke
				(width 0.0127)
				(type default)
			)
			(layer "F.SilkS")
		)
		(fp_line
			(start -1.156208 2.028952)
			(end -0.825246 2.028952)
			(stroke
				(width 0.0127)
				(type default)
			)
			(layer "F.SilkS")
		)
		(fp_line
			(start -1.165606 2.03835)
			(end -0.815594 2.03835)
			(stroke
				(width 0.0127)
				(type default)
			)
			(layer "F.SilkS")
		)
		(fp_line
			(start -1.175258 2.048002)
			(end -0.806196 2.048002)
			(stroke
				(width 0.0127)
				(type default)
			)
			(layer "F.SilkS")
		)
		(fp_line
			(start -1.184656 2.0574)
			(end -0.796544 2.0574)
			(stroke
				(width 0.0127)
				(type default)
			)
			(layer "F.SilkS")
		)
		(fp_line
			(start -1.194308 2.067052)
			(end -0.787146 2.067052)
			(stroke
				(width 0.0127)
				(type default)
			)
			(layer "F.SilkS")
		)
		(fp_line
			(start -1.203706 2.07645)
			(end -0.777494 2.07645)
			(stroke
				(width 0.0127)
				(type default)
			)
			(layer "F.SilkS")
		)
		(fp_line
			(start -1.213358 2.086102)
			(end -0.768096 2.086102)
			(stroke
				(width 0.0127)
				(type default)
			)
			(layer "F.SilkS")
		)
		(fp_line
			(start -1.222756 2.0955)
			(end -0.758444 2.0955)
			(stroke
				(width 0.0127)
				(type default)
			)
			(layer "F.SilkS")
		)
		(fp_line
			(start -1.232408 2.105152)
			(end -0.749046 2.105152)
			(stroke
				(width 0.0127)
				(type default)
			)
			(layer "F.SilkS")
		)
		(fp_line
			(start -1.241806 2.11455)
			(end -0.739394 2.11455)
			(stroke
				(width 0.0127)
				(type default)
			)
			(layer "F.SilkS")
		)
		(fp_line
			(start -1.251458 2.124202)
			(end -0.729996 2.124202)
			(stroke
				(width 0.0127)
				(type default)
			)
			(layer "F.SilkS")
		)
		(fp_line
			(start -1.260856 2.1336)
			(end -0.720344 2.1336)
			(stroke
				(width 0.0127)
				(type default)
			)
			(layer "F.SilkS")
		)
		(fp_line
			(start -1.279144 2.15265)
			(end -0.701294 2.15265)
			(stroke
				(width 0.0127)
				(type default)
			)
			(layer "F.SilkS")
		)
		(fp_line
			(start -1.279398 2.152142)
			(end -0.9906 1.86309)
			(stroke
				(width 0.0127)
				(type default)
			)
			(layer "F.SilkS")
		)
		(fp_line
			(start -1.651 1.778)
			(end 1.651 1.778)
			(stroke
				(width 0.1524)
				(type default)
			)
			(layer "F.SilkS")
		)
		(fp_line
			(start -1.651 -1.778)
			(end -1.651 1.778)
			(stroke
				(width 0.1524)
				(type default)
			)
			(layer "F.SilkS")
		)
		(fp_line
			(start -1.7526 1.8796)
			(end -1.7526 0.9906)
			(stroke
				(width 0.3302)
				(type default)
			)
			(layer "F.SilkS")
		)
		(fp_poly
			(pts
				(xy -1.285748 2.159) (xy -1.285748 1.8796) (xy -1.778 1.8796) (xy -1.778 -1.8796) (xy 1.778 -1.8796)
				(xy 1.778 1.8796) (xy -0.694944 1.8796) (xy -0.694944 2.159)
			)
			(stroke
				(width 0)
				(type default)
			)
			(fill no)
			(layer "F.CrtYd")
		)
		(fp_poly
			(pts
				(xy -1.285748 2.159) (xy -1.285748 1.8796) (xy -1.778 1.8796) (xy -1.778 -1.8796) (xy 1.778 -1.8796)
				(xy 1.778 1.8796) (xy -0.694944 1.8796) (xy -0.694944 2.159)
			)
			(stroke
				(width 0)
				(type default)
			)
			(fill no)
			(layer "F.Fab")
		)
		(pad "1" smd rect
			(at -0.98425 0.9525 180)
			(size 0.762 1.143)
			(layers "F.Cu" "F.Mask" "F.Paste")
			(net "LED_DR_LED1_B")
		)
		(pad "2" smd rect
			(at 0.98425 0.9525 180)
			(size 0.762 1.143)
			(layers "F.Cu" "F.Mask" "F.Paste")
			(net "GND")
		)
		(pad "3" smd rect
			(at 0 -0.9525 180)
			(size 0.762 1.143)
			(layers "F.Cu" "F.Mask" "F.Paste")
			(net "LED_DR_LED1_BLUE")
		)
	)
	(footprint ""
		(layer "F.Cu")
		(at 14.8844 -46.5582 -90)
		(property "Reference" "R174"
			(at 0 0 270)
			(layer "F.SilkS")
			(hide yes)
			(effects
				(font
					(size 1.27 1.27)
				)
			)
		)
		(property "Value" "0R2J-2-GP"
			(at 0.064008 -3.993896 270)
			(unlocked yes)
			(layer "F.Fab")
			(hide yes)
			(effects
				(font
					(size 1.016 1.016)
					(thickness 0.1524)
				)
			)
		)
		(property "Device Type" "R402H16"
			(at 0.064008 -5.517896 270)
			(unlocked yes)
			(layer "F.Fab")
			(hide yes)
			(effects
				(font
					(size 1.016 1.016)
					(thickness 0.1524)
				)
			)
		)
		(duplicate_pad_numbers_are_jumpers no)
		(fp_line
			(start -0.508 -0.9398)
			(end -0.508 0.9398)
			(stroke
				(width 0.1524)
				(type default)
			)
			(layer "F.SilkS")
		)
		(fp_line
			(start 0.508 -0.9398)
			(end -0.508 -0.9398)
			(stroke
				(width 0.1524)
				(type default)
			)
			(layer "F.SilkS")
		)
		(fp_rect
			(start -0.508 0.9398)
			(end 0.508 -0.9398)
			(stroke
				(width 0)
				(type default)
			)
			(fill no)
			(layer "F.CrtYd")
		)
		(fp_rect
			(start -0.508 0.9398)
			(end 0.508 -0.9398)
			(stroke
				(width 0)
				(type default)
			)
			(fill no)
			(layer "F.Fab")
		)
		(pad "1" smd custom
			(at 0 -0.4445 270)
			(size 0.1397 0.1397)
			(layers "F.Cu" "F.Mask" "F.Paste")
			(net "SELF_2A_HB")
			(options
				(clearance outline)
				(anchor circle)
			)
			(primitives
				(gr_poly
					(pts
						(arc
							(start -0.1778 -0.2794)
							(mid -0.249642 -0.249642)
							(end -0.2794 -0.1778)
						)
						(arc
							(start -0.2794 0.1778)
							(mid -0.249642 0.249642)
							(end -0.1778 0.2794)
						)
						(arc
							(start 0.1778 0.2794)
							(mid 0.249642 0.249642)
							(end 0.2794 0.1778)
						)
						(arc
							(start 0.2794 -0.1778)
							(mid 0.249642 -0.249642)
							(end 0.1778 -0.2794)
						)
					)
					(width 0)
					(fill yes)
				)
			)
		)
		(pad "2" smd custom
			(at 0 0.4445 270)
			(size 0.1397 0.1397)
			(layers "F.Cu" "F.Mask" "F.Paste")
			(net "SEB_PEER_1A_HB")
			(options
				(clearance outline)
				(anchor circle)
			)
			(primitives
				(gr_poly
					(pts
						(arc
							(start -0.1778 -0.2794)
							(mid -0.249642 -0.249642)
							(end -0.2794 -0.1778)
						)
						(arc
							(start -0.2794 0.1778)
							(mid -0.249642 0.249642)
							(end -0.1778 0.2794)
						)
						(arc
							(start 0.1778 0.2794)
							(mid 0.249642 0.249642)
							(end 0.2794 0.1778)
						)
						(arc
							(start 0.2794 -0.1778)
							(mid 0.249642 -0.249642)
							(end 0.1778 -0.2794)
						)
					)
					(width 0)
					(fill yes)
				)
			)
		)
	)
	(footprint ""
		(layer "F.Cu")
		(at 33.71469 -150.730966 180)
		(property "Reference" "TP9"
			(at 0 0 180)
			(layer "F.SilkS")
			(hide yes)
			(effects
				(font
					(size 1.27 1.27)
				)
			)
		)
		(property "Value" "TPAD32-GP"
			(at 0 -3.166364 180)
			(unlocked yes)
			(layer "F.Fab")
			(hide yes)
			(effects
				(font
					(size 1.016 1.016)
					(thickness 0.1524)
				)
			)
		)
		(property "Device Type" "TPAD32"
			(at 0 -4.690618 180)
			(unlocked yes)
			(layer "F.Fab")
			(hide yes)
			(effects
				(font
					(size 1.016 1.016)
					(thickness 0.1524)
				)
			)
		)
		(duplicate_pad_numbers_are_jumpers no)
		(fp_poly
			(pts
				(arc
					(start 0.7112 0)
					(mid -0.7112 0)
					(end 0.7112 0)
				)
			)
			(stroke
				(width 0)
				(type default)
			)
			(fill no)
			(layer "F.CrtYd")
		)
		(fp_poly
			(pts
				(arc
					(start 0.7112 0)
					(mid -0.7112 0)
					(end 0.7112 0)
				)
			)
			(stroke
				(width 0)
				(type default)
			)
			(fill no)
			(layer "F.Fab")
		)
		(pad "1" smd circle
			(at 0 0 180)
			(size 0.8128 0.8128)
			(layers "F.Cu" "F.Mask" "F.Paste")
			(net "NCT7904_VSEN10")
		)
	)
	(footprint ""
		(layer "F.Cu")
		(at 12.2428 -55.2196 -90)
		(property "Reference" "R63"
			(at 0 0 270)
			(layer "F.SilkS")
			(hide yes)
			(effects
				(font
					(size 1.27 1.27)
				)
			)
		)
		(property "Value" "0R2J-2-GP"
			(at 0.064008 -3.993896 270)
			(unlocked yes)
			(layer "F.Fab")
			(hide yes)
			(effects
				(font
					(size 1.016 1.016)
					(thickness 0.1524)
				)
			)
		)
		(property "Device Type" "R402H16"
			(at 0.064008 -5.517896 270)
			(unlocked yes)
			(layer "F.Fab")
			(hide yes)
			(effects
				(font
					(size 1.016 1.016)
					(thickness 0.1524)
				)
			)
		)
		(duplicate_pad_numbers_are_jumpers no)
		(fp_line
			(start -0.508 -0.9398)
			(end -0.508 0.9398)
			(stroke
				(width 0.1524)
				(type default)
			)
			(layer "F.SilkS")
		)
		(fp_line
			(start 0.508 -0.9398)
			(end -0.508 -0.9398)
			(stroke
				(width 0.1524)
				(type default)
			)
			(layer "F.SilkS")
		)
		(fp_rect
			(start -0.508 0.9398)
			(end 0.508 -0.9398)
			(stroke
				(width 0)
				(type default)
			)
			(fill no)
			(layer "F.CrtYd")
		)
		(fp_rect
			(start -0.508 0.9398)
			(end 0.508 -0.9398)
			(stroke
				(width 0)
				(type default)
			)
			(fill no)
			(layer "F.Fab")
		)
		(pad "1" smd custom
			(at 0 -0.4445 270)
			(size 0.1397 0.1397)
			(layers "F.Cu" "F.Mask" "F.Paste")
			(net "SELF_TRAY_PRESENT_LOWER")
			(options
				(clearance outline)
				(anchor circle)
			)
			(primitives
				(gr_poly
					(pts
						(arc
							(start -0.1778 -0.2794)
							(mid -0.249642 -0.249642)
							(end -0.2794 -0.1778)
						)
						(arc
							(start -0.2794 0.1778)
							(mid -0.249642 0.249642)
							(end -0.1778 0.2794)
						)
						(arc
							(start 0.1778 0.2794)
							(mid 0.249642 0.249642)
							(end 0.2794 0.1778)
						)
						(arc
							(start 0.2794 -0.1778)
							(mid 0.249642 -0.249642)
							(end 0.1778 -0.2794)
						)
					)
					(width 0)
					(fill yes)
				)
			)
		)
		(pad "2" smd custom
			(at 0 0.4445 270)
			(size 0.1397 0.1397)
			(layers "F.Cu" "F.Mask" "F.Paste")
			(net "PEER_TRAY PRESENT_UPPER")
			(options
				(clearance outline)
				(anchor circle)
			)
			(primitives
				(gr_poly
					(pts
						(arc
							(start -0.1778 -0.2794)
							(mid -0.249642 -0.249642)
							(end -0.2794 -0.1778)
						)
						(arc
							(start -0.2794 0.1778)
							(mid -0.249642 0.249642)
							(end -0.1778 0.2794)
						)
						(arc
							(start 0.1778 0.2794)
							(mid 0.249642 0.249642)
							(end 0.2794 0.1778)
						)
						(arc
							(start 0.2794 -0.1778)
							(mid 0.249642 -0.249642)
							(end 0.1778 -0.2794)
						)
					)
					(width 0)
					(fill yes)
				)
			)
		)
	)
)
